(kicad_pcb
	(version 20260206)
	(generator "pcbnew")
	(generator_version "10.0")
	(general
		(thickness 1.6)
		(legacy_teardrops no)
	)
	(paper "A4")
	(title_block
		(title "04192023_DAF0TMB3IC0_F0TG_MB_C_brd_V02_OCP.brd")
		(comment 1 "Grand Teton / footprints 3387-3393 of 8354")
	)
	(layers
		(0 "F.Cu" signal "TOP")
		(4 "In1.Cu" signal "GND")
		(6 "In2.Cu" signal "IN1")
		(8 "In3.Cu" signal "GND1")
		(10 "In4.Cu" signal "IN2")
		(12 "In5.Cu" signal "GND2")
		(14 "In6.Cu" signal "IN3")
		(16 "In7.Cu" signal "GND3")
		(18 "In8.Cu" signal "VCC")
		(20 "In9.Cu" signal "VCC1")
		(22 "In10.Cu" signal "GND4")
		(24 "In11.Cu" signal "IN4")
		(26 "In12.Cu" signal "GND5")
		(28 "In13.Cu" signal "IN5")
		(30 "In14.Cu" signal "GND6")
		(32 "In15.Cu" signal "IN6")
		(34 "In16.Cu" signal "GND7")
		(2 "B.Cu" signal "BOTTOM")
		(9 "F.Adhes" user "F.Adhesive")
		(11 "B.Adhes" user "B.Adhesive")
		(13 "F.Paste" user "Package Geometry/Pastemask Top")
		(15 "B.Paste" user "Package Geometry/Pastemask Bottom")
		(5 "F.SilkS" user "Ref Des/Silkscreen Top")
		(7 "B.SilkS" user "Ref Des/Silkscreen Bottom")
		(1 "F.Mask" user "Board Geometry/Soldermask Top")
		(3 "B.Mask" user "Board Geometry/Soldermask Bottom")
		(17 "Dwgs.User" user "User.Drawings")
		(19 "Cmts.User" user "User.Comments")
		(21 "Eco1.User" user "User.Eco1")
		(23 "Eco2.User" user "User.Eco2")
		(25 "Edge.Cuts" user "Board Geometry/Outline")
		(27 "Margin" user)
		(31 "F.CrtYd" user "Package Geometry/Place Bound Top")
		(29 "B.CrtYd" user "Package Geometry/Place Bound Bottom")
		(35 "F.Fab" user "Ref Des/Assembly Top")
		(33 "B.Fab" user "Ref Des/Assembly Bottom")
	)
	(footprint ""
		(layer "F.Cu")
		(at 12.99972 -435.600094)
		(property "Reference" "H97"
			(at 4.924044 -4.168394 0)
			(unlocked yes)
			(layer "F.SilkS")
			(effects
				(font
					(size 0.7874 0.5842)
					(thickness 0.1524)
				)
				(justify left)
			)
		)
		(property "Value" ""
			(at 0 0 0)
			(layer "F.Fab")
			(effects
				(font
					(size 1.27 1.27)
				)
			)
		)
		(duplicate_pad_numbers_are_jumpers no)
		(pad "1" thru_hole circle
			(at 0 0)
			(size 10.0076 10.0076)
			(drill 5.6134)
			(layers "*.Cu" "*.Mask")
			(remove_unused_layers no)
			(net "GND")
			(clearance -1.9431)
		)
	)
	(footprint ""
		(layer "F.Cu")
		(at 458.799692 -435.600094)
		(property "Reference" "H103"
			(at -6.63321 -4.534154 0)
			(unlocked yes)
			(layer "F.SilkS")
			(effects
				(font
					(size 0.7874 0.5842)
					(thickness 0.1524)
				)
				(justify left)
			)
		)
		(property "Value" ""
			(at 0 0 0)
			(layer "F.Fab")
			(effects
				(font
					(size 1.27 1.27)
				)
			)
		)
		(duplicate_pad_numbers_are_jumpers no)
		(pad "1" thru_hole circle
			(at 0 0)
			(size 10.0076 10.0076)
			(drill 5.6134)
			(layers "*.Cu" "*.Mask")
			(remove_unused_layers no)
			(net "GND")
			(clearance -1.9431)
		)
	)
	(footprint ""
		(layer "F.Cu")
		(at 73.406 -59.055 -90)
		(property "Reference" "U35"
			(at 0.943102 -2.804668 90)
			(unlocked yes)
			(layer "F.SilkS")
			(effects
				(font
					(size 0.7874 0.5842)
					(thickness 0.1524)
				)
				(justify left)
			)
		)
		(property "Value" ""
			(at 0 0 270)
			(layer "F.Fab")
			(effects
				(font
					(size 1.27 1.27)
				)
			)
		)
		(duplicate_pad_numbers_are_jumpers no)
		(fp_line
			(start -1.733296 1.549908)
			(end 1.733296 1.549908)
			(stroke
				(width 0.1524)
				(type default)
			)
			(layer "F.SilkS")
		)
		(fp_line
			(start 1.733296 1.549908)
			(end 1.733296 -1.549908)
			(stroke
				(width 0.1524)
				(type default)
			)
			(layer "F.SilkS")
		)
		(fp_line
			(start 0 -0.889)
			(end -0.660908 -1.549908)
			(stroke
				(width 0.1524)
				(type default)
			)
			(layer "F.SilkS")
		)
		(fp_line
			(start -1.733296 -1.549908)
			(end -1.733296 1.549908)
			(stroke
				(width 0.1524)
				(type default)
			)
			(layer "F.SilkS")
		)
		(fp_line
			(start -0.660908 -1.549908)
			(end -1.733296 -1.549908)
			(stroke
				(width 0.1524)
				(type default)
			)
			(layer "F.SilkS")
		)
		(fp_line
			(start 0.660908 -1.549908)
			(end 0 -0.889)
			(stroke
				(width 0.1524)
				(type default)
			)
			(layer "F.SilkS")
		)
		(fp_line
			(start 1.733296 -1.549908)
			(end 0.660908 -1.549908)
			(stroke
				(width 0.1524)
				(type default)
			)
			(layer "F.SilkS")
		)
		(fp_poly
			(pts
				(xy -1.80975 -2.293366) (xy -2.223262 -1.998218) (xy -1.721358 -1.73228)
			)
			(stroke
				(width 0)
				(type default)
			)
			(fill yes)
			(layer "F.SilkS")
		)
		(fp_line
			(start -0.849884 1.549908)
			(end 0.849884 1.549908)
			(stroke
				(width 0.1)
				(type default)
			)
			(layer "F.Fab")
		)
		(fp_line
			(start 0.849884 1.549908)
			(end 0.849884 -1.549908)
			(stroke
				(width 0.1)
				(type default)
			)
			(layer "F.Fab")
		)
		(fp_line
			(start -0.849884 -1.549908)
			(end -0.849884 1.549908)
			(stroke
				(width 0.1)
				(type default)
			)
			(layer "F.Fab")
		)
		(fp_line
			(start 0.849884 -1.549908)
			(end -0.849884 -1.549908)
			(stroke
				(width 0.1)
				(type default)
			)
			(layer "F.Fab")
		)
		(fp_poly
			(pts
				(xy -2.4384 -1.20396) (xy -2.4384 -0.69596) (xy -1.9304 -0.94996)
			)
			(stroke
				(width 0)
				(type default)
			)
			(fill yes)
			(layer "F.Fab")
		)
		(pad "1" smd rect
			(at -1.199896 -0.94996 180)
			(size 0.5588 0.8128)
			(layers "F.Cu" "F.Mask" "F.Paste")
			(net "RST_PERST_OCP_V3_2_R_N")
		)
		(pad "2" smd rect
			(at -1.199896 0 180)
			(size 0.5588 0.8128)
			(layers "F.Cu" "F.Mask" "F.Paste")
			(net "HP_LVC3_OCP_V3_2_PWRGD")
		)
		(pad "3" smd rect
			(at -1.199896 0.94996 180)
			(size 0.5588 0.8128)
			(layers "F.Cu" "F.Mask" "F.Paste")
			(net "GND")
		)
		(pad "4" smd rect
			(at 1.199896 0.94996 180)
			(size 0.5588 0.8128)
			(layers "F.Cu" "F.Mask" "F.Paste")
			(net "RST_PERST_OCP_V3_2_BUF_R_N")
		)
		(pad "5" smd rect
			(at 1.199896 -0.94996 180)
			(size 0.5588 0.8128)
			(layers "F.Cu" "F.Mask" "F.Paste")
			(net "P3V3_AUX")
		)
	)
	(footprint ""
		(layer "F.Cu")
		(at 419.597586 -176.338738 -90)
		(property "Reference" "PC599"
			(at 0 0 270)
			(layer "F.SilkS")
			(hide yes)
			(effects
				(font
					(size 1.27 1.27)
				)
			)
		)
		(property "Value" ""
			(at 0 0 270)
			(layer "F.Fab")
			(effects
				(font
					(size 1.27 1.27)
				)
			)
		)
		(duplicate_pad_numbers_are_jumpers no)
		(fp_line
			(start -0.7874 0.4064)
			(end -0.7874 -0.4064)
			(stroke
				(width 0.1524)
				(type default)
			)
			(layer "F.SilkS")
		)
		(fp_line
			(start 0.7874 0.4064)
			(end -0.7874 0.4064)
			(stroke
				(width 0.1524)
				(type default)
			)
			(layer "F.SilkS")
		)
		(fp_line
			(start -0.7874 -0.4064)
			(end 0.7874 -0.4064)
			(stroke
				(width 0.1524)
				(type default)
			)
			(layer "F.SilkS")
		)
		(fp_line
			(start 0.7874 -0.4064)
			(end 0.7874 0.4064)
			(stroke
				(width 0.1524)
				(type default)
			)
			(layer "F.SilkS")
		)
		(fp_line
			(start -0.67945 0.3048)
			(end -0.67945 -0.305054)
			(stroke
				(width 0.1)
				(type default)
			)
			(layer "F.Fab")
		)
		(fp_line
			(start -0.12065 0.3048)
			(end -0.67945 0.3048)
			(stroke
				(width 0.1)
				(type default)
			)
			(layer "F.Fab")
		)
		(fp_line
			(start 0.120396 0.3048)
			(end 0.120396 0.2794)
			(stroke
				(width 0.1)
				(type default)
			)
			(layer "F.Fab")
		)
		(fp_line
			(start 0.67945 0.3048)
			(end 0.120396 0.3048)
			(stroke
				(width 0.1)
				(type default)
			)
			(layer "F.Fab")
		)
		(fp_line
			(start -0.12065 0.2794)
			(end -0.12065 0.3048)
			(stroke
				(width 0.1)
				(type default)
			)
			(layer "F.Fab")
		)
		(fp_line
			(start 0.120396 0.2794)
			(end -0.12065 0.2794)
			(stroke
				(width 0.1)
				(type default)
			)
			(layer "F.Fab")
		)
		(fp_line
			(start -0.12065 -0.2794)
			(end 0.12065 -0.2794)
			(stroke
				(width 0.1)
				(type default)
			)
			(layer "F.Fab")
		)
		(fp_line
			(start 0.12065 -0.2794)
			(end 0.12065 -0.3048)
			(stroke
				(width 0.1)
				(type default)
			)
			(layer "F.Fab")
		)
		(fp_line
			(start 0.12065 -0.3048)
			(end 0.67945 -0.3048)
			(stroke
				(width 0.1)
				(type default)
			)
			(layer "F.Fab")
		)
		(fp_line
			(start 0.67945 -0.3048)
			(end 0.67945 0.3048)
			(stroke
				(width 0.1)
				(type default)
			)
			(layer "F.Fab")
		)
		(fp_line
			(start -0.67945 -0.305054)
			(end -0.12065 -0.305054)
			(stroke
				(width 0.1)
				(type default)
			)
			(layer "F.Fab")
		)
		(fp_line
			(start -0.12065 -0.305054)
			(end -0.12065 -0.2794)
			(stroke
				(width 0.1)
				(type default)
			)
			(layer "F.Fab")
		)
		(pad "1" smd circle
			(at -0.40005 0 270)
			(size 0 0)
			(layers "F.Cu" "F.Mask" "F.Paste")
			(net "PVDDCR_SOC_P0")
		)
		(pad "2" smd circle
			(at 0.40005 0 270)
			(size 0 0)
			(layers "F.Cu" "F.Mask" "F.Paste")
			(net "GND")
		)
	)
	(footprint ""
		(layer "F.Cu")
		(at 119.458486 -428.873412 -90)
		(property "Reference" "U253"
			(at 1.385824 1.781302 90)
			(unlocked yes)
			(layer "F.SilkS")
			(effects
				(font
					(size 0.7874 0.5842)
					(thickness 0.1524)
				)
				(justify left)
			)
		)
		(property "Value" ""
			(at 0 0 270)
			(layer "F.Fab")
			(effects
				(font
					(size 1.27 1.27)
				)
			)
		)
		(duplicate_pad_numbers_are_jumpers no)
		(fp_line
			(start -1.3462 1.100074)
			(end -1.3462 -1.100074)
			(stroke
				(width 0.1524)
				(type default)
			)
			(layer "F.SilkS")
		)
		(fp_line
			(start 1.3462 1.100074)
			(end -1.3462 1.100074)
			(stroke
				(width 0.1524)
				(type default)
			)
			(layer "F.SilkS")
		)
		(fp_line
			(start 0 -0.381)
			(end 0.670052 -1.100074)
			(stroke
				(width 0.1524)
				(type default)
			)
			(layer "F.SilkS")
		)
		(fp_line
			(start -1.3462 -1.100074)
			(end -0.670052 -1.100074)
			(stroke
				(width 0.1524)
				(type default)
			)
			(layer "F.SilkS")
		)
		(fp_line
			(start -0.670052 -1.100074)
			(end 0 -0.381)
			(stroke
				(width 0.1524)
				(type default)
			)
			(layer "F.SilkS")
		)
		(fp_line
			(start 0.670052 -1.100074)
			(end 1.3462 -1.100074)
			(stroke
				(width 0.1524)
				(type default)
			)
			(layer "F.SilkS")
		)
		(fp_line
			(start 1.3462 -1.100074)
			(end 1.3462 1.100074)
			(stroke
				(width 0.1524)
				(type default)
			)
			(layer "F.SilkS")
		)
		(fp_poly
			(pts
				(xy -1.616456 -1.671066) (xy -1.001522 -1.930146) (xy -1.049782 -1.185164)
			)
			(stroke
				(width 0)
				(type default)
			)
			(fill yes)
			(layer "F.SilkS")
		)
		(fp_line
			(start -0.670052 1.100074)
			(end -0.670052 0.8001)
			(stroke
				(width 0.1)
				(type default)
			)
			(layer "F.Fab")
		)
		(fp_line
			(start 0.670052 1.100074)
			(end -0.670052 1.100074)
			(stroke
				(width 0.1)
				(type default)
			)
			(layer "F.Fab")
		)
		(fp_line
			(start -1.100074 0.8001)
			(end -1.100074 -0.8001)
			(stroke
				(width 0.1)
				(type default)
			)
			(layer "F.Fab")
		)
		(fp_line
			(start -0.670052 0.8001)
			(end -1.100074 0.8001)
			(stroke
				(width 0.1)
				(type default)
			)
			(layer "F.Fab")
		)
		(fp_line
			(start -0.670052 0.8001)
			(end -0.670052 -0.8001)
			(stroke
				(width 0.1)
				(type default)
			)
			(layer "F.Fab")
		)
		(fp_line
			(start 0.670052 0.8001)
			(end 0.670052 1.100074)
			(stroke
				(width 0.1)
				(type default)
			)
			(layer "F.Fab")
		)
		(fp_line
			(start 1.100074 0.8001)
			(end 0.670052 0.8001)
			(stroke
				(width 0.1)
				(type default)
			)
			(layer "F.Fab")
		)
		(fp_line
			(start -1.100074 -0.8001)
			(end -0.670052 -0.8001)
			(stroke
				(width 0.1)
				(type default)
			)
			(layer "F.Fab")
		)
		(fp_line
			(start -0.670052 -0.8001)
			(end -0.670052 -1.100074)
			(stroke
				(width 0.1)
				(type default)
			)
			(layer "F.Fab")
		)
		(fp_line
			(start 0.670052 -0.8001)
			(end 0.670052 0.8001)
			(stroke
				(width 0.1)
				(type default)
			)
			(layer "F.Fab")
		)
		(fp_line
			(start 0.670052 -0.8001)
			(end 1.100074 -0.8001)
			(stroke
				(width 0.1)
				(type default)
			)
			(layer "F.Fab")
		)
		(fp_line
			(start 1.100074 -0.8001)
			(end 1.100074 0.8001)
			(stroke
				(width 0.1)
				(type default)
			)
			(layer "F.Fab")
		)
		(fp_line
			(start -0.670052 -1.100074)
			(end 0.670052 -1.100074)
			(stroke
				(width 0.1)
				(type default)
			)
			(layer "F.Fab")
		)
		(fp_line
			(start 0.670052 -1.100074)
			(end 0.670052 -0.8001)
			(stroke
				(width 0.1)
				(type default)
			)
			(layer "F.Fab")
		)
		(fp_poly
			(pts
				(xy -1.524 -0.649986) (xy -2.286 -1.030986) (xy -2.286 -0.268986)
			)
			(stroke
				(width 0)
				(type default)
			)
			(fill yes)
			(layer "F.Fab")
		)
		(pad "1" smd rect
			(at -0.94996 -0.649986 180)
			(size 0.4064 0.508)
			(layers "F.Cu" "F.Mask" "F.Paste")
			(net "GPU_FPGA_BOOT_EN")
		)
		(pad "2" smd rect
			(at -0.94996 0 180)
			(size 0.4064 0.508)
			(layers "F.Cu" "F.Mask" "F.Paste")
			(net "GND")
		)
		(pad "3" smd rect
			(at -0.94996 0.649986 180)
			(size 0.4064 0.508)
			(layers "F.Cu" "F.Mask" "F.Paste")
			(net "GPU_BASE_STBY_EN")
		)
		(pad "4" smd rect
			(at 0.94996 0.649986 180)
			(size 0.4064 0.508)
			(layers "F.Cu" "F.Mask" "F.Paste")
			(net "GPU_BASE_STBY_EN_BUF_R")
		)
		(pad "5" smd rect
			(at 0.94996 0 180)
			(size 0.4064 0.508)
			(layers "F.Cu" "F.Mask" "F.Paste")
			(net "P3V3_AUX")
		)
		(pad "6" smd rect
			(at 0.94996 -0.649986 180)
			(size 0.4064 0.508)
			(layers "F.Cu" "F.Mask" "F.Paste")
			(net "GPU_FPGA_BOOT_EN_BUF_R")
		)
	)
	(footprint ""
		(layer "F.Cu")
		(at 240.792 -285.2928 180)
		(property "Reference" "PC6900"
			(at 0 0 180)
			(layer "F.SilkS")
			(hide yes)
			(effects
				(font
					(size 1.27 1.27)
				)
			)
		)
		(property "Value" ""
			(at 0 0 180)
			(layer "F.Fab")
			(effects
				(font
					(size 1.27 1.27)
				)
			)
		)
		(duplicate_pad_numbers_are_jumpers no)
		(fp_line
			(start 1.524 0.762)
			(end -1.524 0.762)
			(stroke
				(width 0.1524)
				(type default)
			)
			(layer "F.SilkS")
		)
		(fp_line
			(start 1.524 -0.762)
			(end 1.524 0.762)
			(stroke
				(width 0.1524)
				(type default)
			)
			(layer "F.SilkS")
		)
		(fp_line
			(start -1.524 0.762)
			(end -1.524 -0.762)
			(stroke
				(width 0.1524)
				(type default)
			)
			(layer "F.SilkS")
		)
		(fp_line
			(start -1.524 -0.762)
			(end 1.524 -0.762)
			(stroke
				(width 0.1524)
				(type default)
			)
			(layer "F.SilkS")
		)
		(fp_line
			(start 1.1049 0.724916)
			(end 1.1049 -0.724916)
			(stroke
				(width 0.1)
				(type default)
			)
			(layer "F.Fab")
		)
		(fp_line
			(start 1.1049 -0.724916)
			(end -1.1049 -0.724916)
			(stroke
				(width 0.1)
				(type default)
			)
			(layer "F.Fab")
		)
		(fp_line
			(start -1.1049 0.724916)
			(end 1.1049 0.724916)
			(stroke
				(width 0.1)
				(type default)
			)
			(layer "F.Fab")
		)
		(fp_line
			(start -1.1049 -0.724916)
			(end -1.1049 0.724916)
			(stroke
				(width 0.1)
				(type default)
			)
			(layer "F.Fab")
		)
		(pad "1" smd rect
			(at -0.889 0)
			(size 1.016 1.27)
			(layers "F.Cu" "F.Mask" "F.Paste")
			(net "SW_P12V_AUX_P1V8_RETIMER_CPU0_FLT")
		)
		(pad "2" smd rect
			(at 0.889 0)
			(size 1.016 1.27)
			(layers "F.Cu" "F.Mask" "F.Paste")
			(net "GND")
		)
	)
	(footprint ""
		(layer "F.Cu")
		(at 187.221622 -22.727158 -90)
		(property "Reference" "PR4001"
			(at 0 0 270)
			(layer "F.SilkS")
			(hide yes)
			(effects
				(font
					(size 1.27 1.27)
				)
			)
		)
		(property "Value" ""
			(at 0 0 270)
			(layer "F.Fab")
			(effects
				(font
					(size 1.27 1.27)
				)
			)
		)
		(duplicate_pad_numbers_are_jumpers no)
		(fp_line
			(start -0.7874 0.4064)
			(end -0.7874 -0.4064)
			(stroke
				(width 0.1524)
				(type default)
			)
			(layer "F.SilkS")
		)
		(fp_line
			(start 0.7874 0.4064)
			(end -0.7874 0.4064)
			(stroke
				(width 0.1524)
				(type default)
			)
			(layer "F.SilkS")
		)
		(fp_line
			(start -0.7874 -0.4064)
			(end 0.7874 -0.4064)
			(stroke
				(width 0.1524)
				(type default)
			)
			(layer "F.SilkS")
		)
		(fp_line
			(start 0.7874 -0.4064)
			(end 0.7874 0.4064)
			(stroke
				(width 0.1524)
				(type default)
			)
			(layer "F.SilkS")
		)
		(fp_line
			(start -0.67945 0.3048)
			(end -0.67945 -0.305054)
			(stroke
				(width 0.1)
				(type default)
			)
			(layer "F.Fab")
		)
		(fp_line
			(start -0.12065 0.3048)
			(end -0.67945 0.3048)
			(stroke
				(width 0.1)
				(type default)
			)
			(layer "F.Fab")
		)
		(fp_line
			(start 0.120396 0.3048)
			(end 0.120396 0.2794)
			(stroke
				(width 0.1)
				(type default)
			)
			(layer "F.Fab")
		)
		(fp_line
			(start 0.67945 0.3048)
			(end 0.120396 0.3048)
			(stroke
				(width 0.1)
				(type default)
			)
			(layer "F.Fab")
		)
		(fp_line
			(start -0.12065 0.2794)
			(end -0.12065 0.3048)
			(stroke
				(width 0.1)
				(type default)
			)
			(layer "F.Fab")
		)
		(fp_line
			(start 0.120396 0.2794)
			(end -0.12065 0.2794)
			(stroke
				(width 0.1)
				(type default)
			)
			(layer "F.Fab")
		)
		(fp_line
			(start -0.12065 -0.2794)
			(end 0.12065 -0.2794)
			(stroke
				(width 0.1)
				(type default)
			)
			(layer "F.Fab")
		)
		(fp_line
			(start 0.12065 -0.2794)
			(end 0.12065 -0.3048)
			(stroke
				(width 0.1)
				(type default)
			)
			(layer "F.Fab")
		)
		(fp_line
			(start 0.12065 -0.3048)
			(end 0.67945 -0.3048)
			(stroke
				(width 0.1)
				(type default)
			)
			(layer "F.Fab")
		)
		(fp_line
			(start 0.67945 -0.3048)
			(end 0.67945 0.3048)
			(stroke
				(width 0.1)
				(type default)
			)
			(layer "F.Fab")
		)
		(fp_line
			(start -0.67945 -0.305054)
			(end -0.12065 -0.305054)
			(stroke
				(width 0.1)
				(type default)
			)
			(layer "F.Fab")
		)
		(fp_line
			(start -0.12065 -0.305054)
			(end -0.12065 -0.2794)
			(stroke
				(width 0.1)
				(type default)
			)
			(layer "F.Fab")
		)
		(pad "1" smd circle
			(at -0.40005 0 270)
			(size 0 0)
			(layers "F.Cu" "F.Mask" "F.Paste")
			(net "P12V_SCM_UV")
		)
		(pad "2" smd circle
			(at 0.40005 0 270)
			(size 0 0)
			(layers "F.Cu" "F.Mask" "F.Paste")
			(net "P12V_SCM_OV")
		)
	)
)
